# T6G (Grand Teton) — schematic netlist excerpt (pin names and nets, part order shuffled) for the footprints in the layout excerpt that follows; sources: Cadence DE-HDL packaged netlist, KiCad conversion of 04192023_DAF0TMB3IC0_F0TG_MB_C_brd_V02_OCP.brd

R1193  Q_RES  0 5% CHIP  pkg 0402LF  page 141 : A = P12V_OCP_V3_2_BUF_EN_R ; B = P12V_OCP_V3_2_EN_2_R3
PR4527  Q_RES  10M 1% CHIP  pkg 0402LF  page 146 : A = P3V3_E1S_0_R ; B = P3V3_E1S_GATE_0

(kicad_pcb
	(version 20260206)
	(generator "pcbnew")
	(generator_version "10.0")
	(general
		(thickness 1.6)
		(legacy_teardrops no)
	)
	(paper "A4")
	(title_block
		(title "04192023_DAF0TMB3IC0_F0TG_MB_C_brd_V02_OCP.brd")
		(comment 1 "Grand Teton / footprints 1737-1738 of 8354")
	)
	(layers
		(0 "F.Cu" signal "TOP")
		(4 "In1.Cu" signal "GND")
		(6 "In2.Cu" signal "IN1")
		(8 "In3.Cu" signal "GND1")
		(10 "In4.Cu" signal "IN2")
		(12 "In5.Cu" signal "GND2")
		(14 "In6.Cu" signal "IN3")
		(16 "In7.Cu" signal "GND3")
		(18 "In8.Cu" signal "VCC")
		(20 "In9.Cu" signal "VCC1")
		(22 "In10.Cu" signal "GND4")
		(24 "In11.Cu" signal "IN4")
		(26 "In12.Cu" signal "GND5")
		(28 "In13.Cu" signal "IN5")
		(30 "In14.Cu" signal "GND6")
		(32 "In15.Cu" signal "IN6")
		(34 "In16.Cu" signal "GND7")
		(2 "B.Cu" signal "BOTTOM")
		(9 "F.Adhes" user "F.Adhesive")
		(11 "B.Adhes" user "B.Adhesive")
		(13 "F.Paste" user "Package Geometry/Pastemask Top")
		(15 "B.Paste" user "Package Geometry/Pastemask Bottom")
		(5 "F.SilkS" user "Ref Des/Silkscreen Top")
		(7 "B.SilkS" user "Ref Des/Silkscreen Bottom")
		(1 "F.Mask" user "Board Geometry/Soldermask Top")
		(3 "B.Mask" user "Board Geometry/Soldermask Bottom")
		(17 "Dwgs.User" user "User.Drawings")
		(19 "Cmts.User" user "User.Comments")
		(21 "Eco1.User" user "User.Eco1")
		(23 "Eco2.User" user "User.Eco2")
		(25 "Edge.Cuts" user "Board Geometry/Outline")
		(27 "Margin" user)
		(31 "F.CrtYd" user "Package Geometry/Place Bound Top")
		(29 "B.CrtYd" user "Package Geometry/Place Bound Bottom")
		(35 "F.Fab" user "Ref Des/Assembly Top")
		(33 "B.Fab" user "Ref Des/Assembly Bottom")
	)
	(footprint ""
		(layer "F.Cu")
		(at 71.064882 -31.894272 -90)
		(property "Reference" "R1193"
			(at 0 0 270)
			(layer "F.SilkS")
			(hide yes)
			(effects
				(font
					(size 1.27 1.27)
				)
			)
		)
		(property "Value" ""
			(at 0 0 270)
			(layer "F.Fab")
			(effects
				(font
					(size 1.27 1.27)
				)
			)
		)
		(duplicate_pad_numbers_are_jumpers no)
		(fp_line
			(start -0.7874 0.4064)
			(end -0.7874 -0.4064)
			(stroke
				(width 0.1524)
				(type default)
			)
			(layer "F.SilkS")
		)
		(fp_line
			(start 0.7874 0.4064)
			(end -0.7874 0.4064)
			(stroke
				(width 0.1524)
				(type default)
			)
			(layer "F.SilkS")
		)
		(fp_line
			(start -0.7874 -0.4064)
			(end 0.7874 -0.4064)
			(stroke
				(width 0.1524)
				(type default)
			)
			(layer "F.SilkS")
		)
		(fp_line
			(start 0.7874 -0.4064)
			(end 0.7874 0.4064)
			(stroke
				(width 0.1524)
				(type default)
			)
			(layer "F.SilkS")
		)
		(fp_line
			(start -0.67945 0.3048)
			(end -0.67945 -0.305054)
			(stroke
				(width 0.1)
				(type default)
			)
			(layer "F.Fab")
		)
		(fp_line
			(start -0.12065 0.3048)
			(end -0.67945 0.3048)
			(stroke
				(width 0.1)
				(type default)
			)
			(layer "F.Fab")
		)
		(fp_line
			(start 0.120396 0.3048)
			(end 0.120396 0.2794)
			(stroke
				(width 0.1)
				(type default)
			)
			(layer "F.Fab")
		)
		(fp_line
			(start 0.67945 0.3048)
			(end 0.120396 0.3048)
			(stroke
				(width 0.1)
				(type default)
			)
			(layer "F.Fab")
		)
		(fp_line
			(start -0.12065 0.2794)
			(end -0.12065 0.3048)
			(stroke
				(width 0.1)
				(type default)
			)
			(layer "F.Fab")
		)
		(fp_line
			(start 0.120396 0.2794)
			(end -0.12065 0.2794)
			(stroke
				(width 0.1)
				(type default)
			)
			(layer "F.Fab")
		)
		(fp_line
			(start -0.12065 -0.2794)
			(end 0.12065 -0.2794)
			(stroke
				(width 0.1)
				(type default)
			)
			(layer "F.Fab")
		)
		(fp_line
			(start 0.12065 -0.2794)
			(end 0.12065 -0.3048)
			(stroke
				(width 0.1)
				(type default)
			)
			(layer "F.Fab")
		)
		(fp_line
			(start 0.12065 -0.3048)
			(end 0.67945 -0.3048)
			(stroke
				(width 0.1)
				(type default)
			)
			(layer "F.Fab")
		)
		(fp_line
			(start 0.67945 -0.3048)
			(end 0.67945 0.3048)
			(stroke
				(width 0.1)
				(type default)
			)
			(layer "F.Fab")
		)
		(fp_line
			(start -0.67945 -0.305054)
			(end -0.12065 -0.305054)
			(stroke
				(width 0.1)
				(type default)
			)
			(layer "F.Fab")
		)
		(fp_line
			(start -0.12065 -0.305054)
			(end -0.12065 -0.2794)
			(stroke
				(width 0.1)
				(type default)
			)
			(layer "F.Fab")
		)
		(pad "1" smd circle
			(at -0.40005 0 270)
			(size 0 0)
			(layers "F.Cu" "F.Mask" "F.Paste")
			(net "P12V_OCP_V3_2_BUF_EN_R")
		)
		(pad "2" smd circle
			(at 0.40005 0 270)
			(size 0 0)
			(layers "F.Cu" "F.Mask" "F.Paste")
			(net "P12V_OCP_V3_2_EN_2_R3")
		)
	)
	(footprint ""
		(layer "F.Cu")
		(at 223.384364 -75.53071 180)
		(property "Reference" "PR4527"
			(at 0 0 180)
			(layer "F.SilkS")
			(hide yes)
			(effects
				(font
					(size 1.27 1.27)
				)
			)
		)
		(property "Value" ""
			(at 0 0 180)
			(layer "F.Fab")
			(effects
				(font
					(size 1.27 1.27)
				)
			)
		)
		(duplicate_pad_numbers_are_jumpers no)
		(fp_line
			(start 0.7874 0.4064)
			(end -0.7874 0.4064)
			(stroke
				(width 0.1524)
				(type default)
			)
			(layer "F.SilkS")
		)
		(fp_line
			(start 0.7874 -0.4064)
			(end 0.7874 0.4064)
			(stroke
				(width 0.1524)
				(type default)
			)
			(layer "F.SilkS")
		)
		(fp_line
			(start -0.7874 0.4064)
			(end -0.7874 -0.4064)
			(stroke
				(width 0.1524)
				(type default)
			)
			(layer "F.SilkS")
		)
		(fp_line
			(start -0.7874 -0.4064)
			(end 0.7874 -0.4064)
			(stroke
				(width 0.1524)
				(type default)
			)
			(layer "F.SilkS")
		)
		(fp_line
			(start 0.67945 0.3048)
			(end 0.120396 0.3048)
			(stroke
				(width 0.1)
				(type default)
			)
			(layer "F.Fab")
		)
		(fp_line
			(start 0.67945 -0.3048)
			(end 0.67945 0.3048)
			(stroke
				(width 0.1)
				(type default)
			)
			(layer "F.Fab")
		)
		(fp_line
			(start 0.12065 -0.2794)
			(end 0.12065 -0.3048)
			(stroke
				(width 0.1)
				(type default)
			)
			(layer "F.Fab")
		)
		(fp_line
			(start 0.12065 -0.3048)
			(end 0.67945 -0.3048)
			(stroke
				(width 0.1)
				(type default)
			)
			(layer "F.Fab")
		)
		(fp_line
			(start 0.120396 0.3048)
			(end 0.120396 0.2794)
			(stroke
				(width 0.1)
				(type default)
			)
			(layer "F.Fab")
		)
		(fp_line
			(start 0.120396 0.2794)
			(end -0.12065 0.2794)
			(stroke
				(width 0.1)
				(type default)
			)
			(layer "F.Fab")
		)
		(fp_line
			(start -0.12065 0.3048)
			(end -0.67945 0.3048)
			(stroke
				(width 0.1)
				(type default)
			)
			(layer "F.Fab")
		)
		(fp_line
			(start -0.12065 0.2794)
			(end -0.12065 0.3048)
			(stroke
				(width 0.1)
				(type default)
			)
			(layer "F.Fab")
		)
		(fp_line
			(start -0.12065 -0.2794)
			(end 0.12065 -0.2794)
			(stroke
				(width 0.1)
				(type default)
			)
			(layer "F.Fab")
		)
		(fp_line
			(start -0.12065 -0.305054)
			(end -0.12065 -0.2794)
			(stroke
				(width 0.1)
				(type default)
			)
			(layer "F.Fab")
		)
		(fp_line
			(start -0.67945 0.3048)
			(end -0.67945 -0.305054)
			(stroke
				(width 0.1)
				(type default)
			)
			(layer "F.Fab")
		)
		(fp_line
			(start -0.67945 -0.305054)
			(end -0.12065 -0.305054)
			(stroke
				(width 0.1)
				(type default)
			)
			(layer "F.Fab")
		)
		(pad "1" smd circle
			(at -0.40005 0 180)
			(size 0 0)
			(layers "F.Cu" "F.Mask" "F.Paste")
			(net "P3V3_E1S_0_R")
		)
		(pad "2" smd circle
			(at 0.40005 0 180)
			(size 0 0)
			(layers "F.Cu" "F.Mask" "F.Paste")
			(net "P3V3_E1S_GATE_0")
		)
	)
)
